# S9S_MB_2U (Grand Teton) — schematic netlist excerpt (pin names and nets, part order shuffled) for the footprints in the layout excerpt that follows; sources: Cadence DE-HDL packaged netlist, KiCad conversion of 03242023_DA0F0TMBIJ0_F0T_Motherboard_J_brd_V01_OCP.brd

R4571  Q_RES  0 5% EMPTY  pkg 0402LF  page 145 : A = GPU_3V3IO_RSVD4 ; B = GPU_3V3IO_RSVD4_ISO
PC477  Q_CAP  10UF 6.3V 20% X6S  pkg C0402  page 292 : A = PVCCINFAON_CPU1_VREF ; B = GND

(kicad_pcb
	(version 20260206)
	(generator "pcbnew")
	(generator_version "10.0")
	(general
		(thickness 1.6)
		(legacy_teardrops no)
	)
	(paper "A4")
	(title_block
		(title "03242023_DA0F0TMBIJ0_F0T_Motherboard_J_brd_V01_OCP.brd")
		(comment 1 "Grand Teton / footprints 172-173 of 6105")
	)
	(layers
		(0 "F.Cu" signal "TOP")
		(4 "In1.Cu" signal "GND")
		(6 "In2.Cu" signal "IN1")
		(8 "In3.Cu" signal "GND1")
		(10 "In4.Cu" signal "IN2")
		(12 "In5.Cu" signal "GND2")
		(14 "In6.Cu" signal "IN3")
		(16 "In7.Cu" signal "GND3")
		(18 "In8.Cu" signal "VCC")
		(20 "In9.Cu" signal "VCC1")
		(22 "In10.Cu" signal "GND4")
		(24 "In11.Cu" signal "IN4")
		(26 "In12.Cu" signal "GND5")
		(28 "In13.Cu" signal "IN5")
		(30 "In14.Cu" signal "GND6")
		(32 "In15.Cu" signal "IN6")
		(34 "In16.Cu" signal "GND7")
		(2 "B.Cu" signal "BOTTOM")
		(9 "F.Adhes" user "F.Adhesive")
		(11 "B.Adhes" user "B.Adhesive")
		(13 "F.Paste" user "Package Geometry/Pastemask Top")
		(15 "B.Paste" user "Package Geometry/Pastemask Bottom")
		(5 "F.SilkS" user "Ref Des/Silkscreen Top")
		(7 "B.SilkS" user "Ref Des/Silkscreen Bottom")
		(1 "F.Mask" user "Board Geometry/Soldermask Top")
		(3 "B.Mask" user "Board Geometry/Soldermask Bottom")
		(17 "Dwgs.User" user "User.Drawings")
		(19 "Cmts.User" user "User.Comments")
		(21 "Eco1.User" user "User.Eco1")
		(23 "Eco2.User" user "User.Eco2")
		(25 "Edge.Cuts" user "Board Geometry/Outline")
		(27 "Margin" user)
		(31 "F.CrtYd" user "Package Geometry/Place Bound Top")
		(29 "B.CrtYd" user "Package Geometry/Place Bound Bottom")
		(35 "F.Fab" user "Ref Des/Assembly Top")
		(33 "B.Fab" user "Ref Des/Assembly Bottom")
	)
	(footprint ""
		(layer "F.Cu")
		(at 29.869638 -125.194314 -90)
		(property "Reference" "PC477"
			(at 0 0 270)
			(layer "F.SilkS")
			(hide yes)
			(effects
				(font
					(size 1.27 1.27)
				)
			)
		)
		(property "Value" ""
			(at 0 0 270)
			(layer "F.Fab")
			(effects
				(font
					(size 1.27 1.27)
				)
			)
		)
		(duplicate_pad_numbers_are_jumpers no)
		(fp_line
			(start -0.7874 0.4064)
			(end -0.7874 -0.4064)
			(stroke
				(width 0.1524)
				(type default)
			)
			(layer "F.SilkS")
		)
		(fp_line
			(start 0.7874 0.4064)
			(end -0.7874 0.4064)
			(stroke
				(width 0.1524)
				(type default)
			)
			(layer "F.SilkS")
		)
		(fp_line
			(start -0.7874 -0.4064)
			(end 0.7874 -0.4064)
			(stroke
				(width 0.1524)
				(type default)
			)
			(layer "F.SilkS")
		)
		(fp_line
			(start 0.7874 -0.4064)
			(end 0.7874 0.4064)
			(stroke
				(width 0.1524)
				(type default)
			)
			(layer "F.SilkS")
		)
		(fp_line
			(start -0.67945 0.3048)
			(end -0.67945 -0.305054)
			(stroke
				(width 0.1)
				(type default)
			)
			(layer "F.Fab")
		)
		(fp_line
			(start -0.12065 0.3048)
			(end -0.67945 0.3048)
			(stroke
				(width 0.1)
				(type default)
			)
			(layer "F.Fab")
		)
		(fp_line
			(start 0.120396 0.3048)
			(end 0.120396 0.2794)
			(stroke
				(width 0.1)
				(type default)
			)
			(layer "F.Fab")
		)
		(fp_line
			(start 0.67945 0.3048)
			(end 0.120396 0.3048)
			(stroke
				(width 0.1)
				(type default)
			)
			(layer "F.Fab")
		)
		(fp_line
			(start -0.12065 0.2794)
			(end -0.12065 0.3048)
			(stroke
				(width 0.1)
				(type default)
			)
			(layer "F.Fab")
		)
		(fp_line
			(start 0.120396 0.2794)
			(end -0.12065 0.2794)
			(stroke
				(width 0.1)
				(type default)
			)
			(layer "F.Fab")
		)
		(fp_line
			(start -0.12065 -0.2794)
			(end 0.12065 -0.2794)
			(stroke
				(width 0.1)
				(type default)
			)
			(layer "F.Fab")
		)
		(fp_line
			(start 0.12065 -0.2794)
			(end 0.12065 -0.3048)
			(stroke
				(width 0.1)
				(type default)
			)
			(layer "F.Fab")
		)
		(fp_line
			(start 0.12065 -0.3048)
			(end 0.67945 -0.3048)
			(stroke
				(width 0.1)
				(type default)
			)
			(layer "F.Fab")
		)
		(fp_line
			(start 0.67945 -0.3048)
			(end 0.67945 0.3048)
			(stroke
				(width 0.1)
				(type default)
			)
			(layer "F.Fab")
		)
		(fp_line
			(start -0.67945 -0.305054)
			(end -0.12065 -0.305054)
			(stroke
				(width 0.1)
				(type default)
			)
			(layer "F.Fab")
		)
		(fp_line
			(start -0.12065 -0.305054)
			(end -0.12065 -0.2794)
			(stroke
				(width 0.1)
				(type default)
			)
			(layer "F.Fab")
		)
		(pad "1" smd circle
			(at -0.40005 0 270)
			(size 0 0)
			(layers "F.Cu" "F.Mask" "F.Paste")
			(net "PVCCINFAON_CPU1_VREF")
		)
		(pad "2" smd circle
			(at 0.40005 0 270)
			(size 0 0)
			(layers "F.Cu" "F.Mask" "F.Paste")
			(net "GND")
		)
	)
	(footprint ""
		(layer "F.Cu")
		(at 355.219 -393.283948 180)
		(property "Reference" "R4571"
			(at 0 0 180)
			(layer "F.SilkS")
			(hide yes)
			(effects
				(font
					(size 1.27 1.27)
				)
			)
		)
		(property "Value" ""
			(at 0 0 180)
			(layer "F.Fab")
			(effects
				(font
					(size 1.27 1.27)
				)
			)
		)
		(duplicate_pad_numbers_are_jumpers no)
		(fp_line
			(start 0.7874 0.4064)
			(end -0.7874 0.4064)
			(stroke
				(width 0.1524)
				(type default)
			)
			(layer "F.SilkS")
		)
		(fp_line
			(start 0.7874 -0.4064)
			(end 0.7874 0.4064)
			(stroke
				(width 0.1524)
				(type default)
			)
			(layer "F.SilkS")
		)
		(fp_line
			(start -0.7874 0.4064)
			(end -0.7874 -0.4064)
			(stroke
				(width 0.1524)
				(type default)
			)
			(layer "F.SilkS")
		)
		(fp_line
			(start -0.7874 -0.4064)
			(end 0.7874 -0.4064)
			(stroke
				(width 0.1524)
				(type default)
			)
			(layer "F.SilkS")
		)
		(fp_line
			(start 0.67945 0.3048)
			(end 0.120396 0.3048)
			(stroke
				(width 0.1)
				(type default)
			)
			(layer "F.Fab")
		)
		(fp_line
			(start 0.67945 -0.3048)
			(end 0.67945 0.3048)
			(stroke
				(width 0.1)
				(type default)
			)
			(layer "F.Fab")
		)
		(fp_line
			(start 0.12065 -0.2794)
			(end 0.12065 -0.3048)
			(stroke
				(width 0.1)
				(type default)
			)
			(layer "F.Fab")
		)
		(fp_line
			(start 0.12065 -0.3048)
			(end 0.67945 -0.3048)
			(stroke
				(width 0.1)
				(type default)
			)
			(layer "F.Fab")
		)
		(fp_line
			(start 0.120396 0.3048)
			(end 0.120396 0.2794)
			(stroke
				(width 0.1)
				(type default)
			)
			(layer "F.Fab")
		)
		(fp_line
			(start 0.120396 0.2794)
			(end -0.12065 0.2794)
			(stroke
				(width 0.1)
				(type default)
			)
			(layer "F.Fab")
		)
		(fp_line
			(start -0.12065 0.3048)
			(end -0.67945 0.3048)
			(stroke
				(width 0.1)
				(type default)
			)
			(layer "F.Fab")
		)
		(fp_line
			(start -0.12065 0.2794)
			(end -0.12065 0.3048)
			(stroke
				(width 0.1)
				(type default)
			)
			(layer "F.Fab")
		)
		(fp_line
			(start -0.12065 -0.2794)
			(end 0.12065 -0.2794)
			(stroke
				(width 0.1)
				(type default)
			)
			(layer "F.Fab")
		)
		(fp_line
			(start -0.12065 -0.305054)
			(end -0.12065 -0.2794)
			(stroke
				(width 0.1)
				(type default)
			)
			(layer "F.Fab")
		)
		(fp_line
			(start -0.67945 0.3048)
			(end -0.67945 -0.305054)
			(stroke
				(width 0.1)
				(type default)
			)
			(layer "F.Fab")
		)
		(fp_line
			(start -0.67945 -0.305054)
			(end -0.12065 -0.305054)
			(stroke
				(width 0.1)
				(type default)
			)
			(layer "F.Fab")
		)
		(pad "1" smd circle
			(at -0.40005 0 180)
			(size 0 0)
			(layers "F.Cu" "F.Mask" "F.Paste")
			(net "GPU_3V3IO_RSVD4")
		)
		(pad "2" smd circle
			(at 0.40005 0 180)
			(size 0 0)
			(layers "F.Cu" "F.Mask" "F.Paste")
			(net "GPU_3V3IO_RSVD4_ISO")
		)
	)
)
